1
1
2
2
3
3
4
4
5
5
6
6
D D
C C
B B
A A
timingcard.com
1SHEET OF 7
GNDGND
+3.3V+3.3V
+3.3V+3.3V+3.3V+3.3V
KEY2KEY1
LED1 LED2 LED3 LED4
RED
D14
RED
D13
RED
D12
RED
D11
1.0K
R36
1.0K
R35
10K
R34
10K
R33
SPST-NO
12
S5
SPST-NO
12
S6
LEDS
BUTTONS
SMCJ6.5
D15
SMCJ6.5
D17
SMCJ6.5
D18
SMCJ6.5
D16
GND GND
GND
GND
ANT1
ANT2
ANT4ANT3
PPS INPUT/OUTPUT
0 Ohm
R31
MAC10M
0 Ohm
R15
MACPPSI 0 Ohm
R14
MACPPSO
GPS1_TP1
0 Ohm
R32
GPS1
R16
200 OHM
R28
200 OHM
R29
200 OHM
R30
200 OHM
MAC_FREQ_CTRL
MAC_PPS_OUT+
MAC_PPS_IN0+
1
2
3
J6
1909763-1
5
1
2
3
4
J8
901-143-6RFX
1
2
3
J5
1909763-1
5
1
2
3
4
J7
901-143-6RFX
1
2
3
J10
1909763-1
5
1
2
3
4
J12
901-143-6RFX
1
2
3
J9
1909763-1
5
1
2
3
4
J11
901-143-6RFX
GND
GND GND
GND
PID1101 
PID1102 
COD11 
PID1201 
PID1202 
COD12 
PID1301 
PID1302 
COD13 
PID1401 
PID1402 
COD14 
PID150A 
PID150K 
COD15 PID160A 
PID160K 
COD16 
PID170A 
PID170K 
COD17 
PID180A 
PID180K 
COD18 
PIJ501 
PIJ502 
PIJ503 
COJ5 
PIJ601 
PIJ602 
PIJ603 
COJ6 
PIJ701 
PIJ702 PIJ703 PIJ704 PIJ705 
COJ7 
PIJ801 
PIJ802 PIJ803 PIJ804 PIJ805 
COJ8 
PIJ901 
PIJ902 
PIJ903 
COJ9 
PIJ1001 
PIJ1002 
PIJ1003 
COJ10 
PIJ1101 
PIJ1102 PIJ1103 PIJ1104 PIJ1105 
COJ11 
PIJ1201 
PIJ1202 PIJ1203 PIJ1204 PIJ1205 
COJ12 
PIR1401 
PIR1402 
COR14 PIR1501 
PIR1502 
COR15 
PIR1601 
PIR1602 COR16 
PIR2801 
PIR2802 COR28 
PIR2901 
PIR2902 COR29 
PIR3001 
PIR3002 COR30 
PIR3101 
PIR3102 
COR31 
PIR3201 
PIR3202 
COR32 
PIR3301 
PIR3302 
COR33 
PIR3401 
PIR3402 
COR34 
PIR3501 PIR3502 
COR35 
PIR3601 PIR3602 
COR36 
PIS501 PIS502 
COS5 
PIS601 PIS602 
COS6 



1
1
2
2
3
3
4
4
5
5
6
6
D D
C C
B B
A A
timingcard.com
2SHEET OF 7
11
S1
Screw_2.9
11
S2
Screw_2.9
11
S3
Screw_2.9
11
S4
Screw_2.9
+12V
GND
GND
GND
+5.0V
+3.3V
GND GND
GNDGND GND
+3.3V+12V
+12V
2.1X5.5MM
24V
2.5A
R/A TH
PJ-002A
2
3
1
J1
39V
DFLZ39
D1
39V
DFLZ39
D2
39V
DFLZ39
D3
2X3
6
5
4
3
2
1J2
SW-SPST
12
SW1
10uF
C1
10uF
C6
10uF
C14
10uF
C13
10uF
C5
10uF
C7
10uF
C8
RED
D4
200 OHM
R1
47K
R2
2.2K
R8
10K
R6
47K
R4
0.01uF
C4
10.uH
L1
10.uH
L2
0.01uF
C3
47K
R3
10K
R7
2.2K
R9
26.1K
R5
MP1482DS
BS 1
IN 2
SW 3
FB 5
EN7
SS8
GND4
COMP6
U1
MP1482DS
BS 1
IN 2
SW 3
FB 5
EN7
SS8
GND4
COMP6
U2
+12V_PCIE
2.00A
F1
C20.1uF
C150.1uF C160.1uF C170.1uF C180.1uFC19
0.1uF
C210.1uF
C9
0.1uF
C100.1uF C110.1uF C120.1uF
C22
0.033uF
C20
0.033uF
PIC101 
PIC102 
COC1 
PIC201 
PIC202 COC2 
PIC301 PIC302 
COC3 
PIC401 PIC402 
COC4 
PIC501 
PIC502 
COC5 
PIC601 
PIC602 
COC6 
PIC701 
PIC702 
COC7 PIC801 
PIC802 
COC8 
PIC901 
PIC902 
COC9 
PIC1001 
PIC1002 
COC10 
PIC1101 
PIC1102 
COC11 
PIC1201 
PIC1202 
COC12 PIC1301 
PIC1302 
COC13 PIC1401 
PIC1402 
COC14 
PIC1501 
PIC1502 
COC15 
PIC1601 
PIC1602 
COC16 
PIC1701 
PIC1702 
COC17 
PIC1801 
PIC1802 
COC18 
PIC1901 
PIC1902 COC19 
PIC2001 
PIC2002 
COC20 
PIC2101 
PIC2102 
COC21 
PIC2201 
PIC2202 
COC22 
PID101 PID102 
COD1 
PID201 PID202 
COD2 
PID301 PID302 
COD3 
PID401 
PID402 
COD4 
PIF101 PIF102 
COF1 
PIJ101 
PIJ102 
PIJ103 
COJ1 
PIJ201 
PIJ202 
PIJ203 
PIJ204 
PIJ205 
PIJ206 
COJ2 
PIL101 PIL102 
COL1 
PIL201 PIL202 
COL2 
PIR101 
PIR102 
COR1 
PIR201 
PIR202 
COR2 
PIR301 
PIR302 
COR3 
PIR401 PIR402 
COR4 
PIR501 PIR502 
COR5 
PIR601 
PIR602 
COR6 
PIR701 
PIR702 
COR7 
PIR801 PIR802 
COR8 
PIR901 PIR902 
COR9 
PIS101 
COS1 
PIS201 
COS2 
PIS301 
COS3 
PIS401 
COS4 
PISW101 PISW102 
COSW1 
PIU101 PIU102 
PIU103 
PIU104 
PIU105 
PIU106 
PIU107 
PIU108 
COU1 PIU201 PIU202 
PIU203 
PIU204 
PIU205 
PIU206 
PIU207 
PIU208 
COU2 



1
1
2
2
3
3
4
4
5
5
6
6
D D
C C
B B
A A
timingcard.com
3SHEET OF 7
GND GND
+12V_PCIE+3.3V_PCIE
+3.3V
+3.3V_PCIE
+12V_PCIE
PCIE_RX0_P
PCIE_RX0_N
PCIE_RX1_P
PCIE_RX1_N
PCIE_RX2_P
PCIE_RX2_N
PCIE_RX3_P
PCIE_RX3_N
PCIE_PERST
PCIE_CLK_P
PCIE_CLK_N
PCIE_TX0_P
PCIE_TX0_N
PCIE_TX1_P
PCIE_TX1_N
PCIE_TX2_P
PCIE_TX2_N
PCIE_TX3_P
PCIE_TX3_N
PCIe Connector
4.7K
R22
0.1UFC53
0.1UFC52
0 OHM
R24
0 OHM
R23
0.1UFC51
0.1UFC49
0.1UFC47
0.1UFC45
0.1UFC44
0.1UFC46
0.1UFC48
0.1UFC50
KEY KEY
+12v1B1
+12V2B2
+12V3B3
GND1B4
SMCLKB5
SMDATAB6
GND2B7
+3.3V1B8
JTAG/TRST_nB9
+3.3vauxB10
WAKE_nB11
RESERVED1B12
GND3B13
PETp0B14
PETn0B15
GND4B16
PRSNT2_nB17
GND5B18
PETp1B19
PETn1B20
GND6B21
GND7B22
PETp2B23
PETn2B24
GND8B25
GND9B26
PETp3B27
PETn3B28
GND10B29
RESERVED2B30
PRSNT4_nB31
GND11B32
PRSNT1_n A1
+12V5 A2
+12V4 A3
GND37 A4
JTAG/TCK A5
JTAG/TDI A6
JTAG/TDO A7
JTAG/TMS A8
+3.3V3 A9
+3.3V2 A10
PERST A11
GND36 A12
REFCLK+ A13
REFCLK- A14
GND35 A15
PERp0 A16
PERn0 A17
GND34 A18
RESERVED5 A19
GND33 A20
PERp1 A21
PERn1 A22
GND32 A23
GND31 A24
PERp2 A25
PERn2 A26
GND30 A27
GND29 A28
PERp3 A29
PERn3 A30
GND28 A31
RESERVED4 A32
P2
PCIex4
GND
+3.3V
GND GND GND GND+3.3V +3.3V +3.3V +3.3V
FPGA_TCK
FPGA_TDO
FPGA_TMS
FPGA_TDI
JTAG
33 OHM
R18
33 OHM
R19
33 OHM
R20
33 OHM
R21
2X5
9
3
10
4
1
5
7
2
6
8
U5
BAT54SW
2
3
1
D8
BAT54SW
2
3
1
D7
BAT54SW
2
3
1
D6
BAT54SW
2
3
1
D5
PRSNT
PRSNT
PRSNT
FPGA_TCK FPGA_TDO FPGA_TMS FPGA_TDI
PIC4401 PIC4402 
COC44 
PIC4501 PIC4502 
COC45 
PIC4601 PIC4602 
COC46 
PIC4701 PIC4702 
COC47 
PIC4801 PIC4802 
COC48 
PIC4901 PIC4902 
COC49 
PIC5001 PIC5002 
COC50 
PIC5101 PIC5102 
COC51 
PIC5201 PIC5202 
COC52 
PIC5301 PIC5302 
COC53 
PID501 PID502 
PID503 
COD5 
PID601 PID602 
PID603 
COD6 
PID701 PID702 
PID703 
COD7 
PID801 PID802 
PID803 
COD8 
PIP20A1 
PIP20A2 
PIP20A3 
PIP20A4 
PIP20A5 
PIP20A6 
PIP20A7 
PIP20A8 
PIP20A9 
PIP20A10 
PIP20A11 
PIP20A12 
PIP20A13 
PIP20A14 
PIP20A15 
PIP20A16 
PIP20A17 
PIP20A18 
PIP20A19 
PIP20A20 
PIP20A21 
PIP20A22 
PIP20A23 
PIP20A24 
PIP20A25 
PIP20A26 
PIP20A27 
PIP20A28 
PIP20A29 
PIP20A30 
PIP20A31 
PIP20A32 
PIP20B1 
PIP20B2 
PIP20B3 
PIP20B4 
PIP20B5 
PIP20B6 
PIP20B7 
PIP20B8 
PIP20B9 
PIP20B10 
PIP20B11 
PIP20B12 
PIP20B13 
PIP20B14 
PIP20B15 
PIP20B16 
PIP20B17 
PIP20B18 
PIP20B19 
PIP20B20 
PIP20B21 
PIP20B22 
PIP20B23 
PIP20B24 
PIP20B25 
PIP20B26 
PIP20B27 
PIP20B28 
PIP20B29 
PIP20B30 
PIP20B31 
PIP20B32 
COP2 
PIR1801 PIR1802 
COR18 
PIR1901 PIR1902 
COR19 
PIR2001 PIR2002 
COR20 
PIR2101 PIR2102 
COR21 
PIR2201 
PIR2202 
COR22 
PIR2301 PIR2302 
COR23 
PIR2401 PIR2402 
COR24 
PIU501 PIU502 
PIU503 PIU504 
PIU505 PIU506 
PIU507 PIU508 
PIU509 PIU5010 
COU5 



1
1
2
2
3
3
4
4
5
5
6
6
D D
C C
B B
A A
timingcard.com
4SHEET OF 7
+3.3V
GND
UART1_RXD
UART1_TXD
UART
RED
D9
RED
D10
1.0UF
C54
10.UF
C55
USB MINI B
V_BUS (RED)1
DM (WHT)2
DP (GRN)3
ID4
GND (BLK)5
J3
GND
10K
R27
FT230XS
USBDP 8
CTS#6
RESET# 11
VCC 12
VCCIO 3
TXD1
RTS#2 3V3OUT 10
USBDM 9
RXD4
CBUS316
CBUS015
CBUS27 CBUS114
GND13
GND5
U6
GND
R25
499 OHM
R26
499 OHM
PIC5401 
PIC5402 
COC54 PIC5501 
PIC5502 
COC55 PID901 
PID902 
COD9 
PID1001 
PID1002 
COD10 
PIJ301 
PIJ302 
PIJ303 
PIJ304 
PIJ305 
COJ3 
PIR2501 
PIR2502 COR25 
PIR2601 
PIR2602 COR26 
PIR2701 PIR2702 
COR27 
PIU601 
PIU602 
PIU603 
PIU604 
PIU605 
PIU606 
PIU607 
PIU608 
PIU609 
PIU6010 
PIU6011 
PIU6012 
PIU6013 
PIU6014 
PIU6015 
PIU6016 
COU6 



1
1
2
2
3
3
4
4
5
5
6
6
D D
C C
B B
A A
timingcard.com
5SHEET OF 7
+5.0V
GND
+3.3V
GND GND
GPS1_TP2
GPS1_TP1
GPS1_RX
GPS1_TX
GPS1_RST
GPS
10uF
C58
10uF
C60
VCC_ANT1
VCC2
TXD3
RST4 RXD 5TP1 6TP2 7GND 8
U9
RCB-F9T
+5.0V
GND
+3.3V
GND GND
GPS2_TP2
GPS2_TP1
GPS2_RX
GPS2_TX
GPS2_RST10uF
C87
10uF
C89
VCC_ANT1
VCC2
TXD3
RST4 RXD 5TP1 6TP2 7GND 8
U14
RCB-F9T
GND
1.0UF
C91
10.UF
C92
GND
10K
R43
FT230XS
USBDP 8
CTS#6
RESET# 11
VCC 12
VCCIO 3
TXD1
RTS#2 3V3OUT 10
USBDM 9
RXD4
CBUS316
CBUS015
CBUS27 CBUS114
GND13
GND5
U16
+5.0V
GND
GPS1_TX
GPS1_RX
1X3
11
22
33
JP1
1X3
11
22
33
JP2
USB MICRO B
V_BUS (RED)1
DM (WHT)2
DP (GRN)3
ID4
GND (BLK)5
J4
GPS2_RX
GPS2_TX
GND GND
+3.3V
GND
+3.3V
IMU_ENV_SCL
IMU_ENV_SDA
MOSI
CSN
SCK
MISO
IMU_BOOT
IMU_PS1
IMU_PS0
IMU_CLKSEL0
IMU_NRST
IMU_INT
IMU
10uF
C56
BNO080
NC1
GND2
VDD3
BOOTN4
PS15
PS0/WAKE6
NC7
NC8
CAP9
CLKSEL010
NRST11
NC12
NC13
H_INTN14 ENV_SCL 15ENV_SDA 16SA0/H_MOSI 17H_CSN 18H_SCL/SCK/RX 19H_SDA/H_MISO/TX 20NC 21NC 22NC 23NC 24GND 25XOUT32/CLKSEL1 26XIN32 27VDDIO 28
U8
32.768kHz
41
32
X1
22pF
C86
22pF
C85
GND
GPS UART
MAC_RX
MAC_TX
0 Ohm
R10
GPS2TX
0 Ohm
R11
MACTX
0 Ohm
R12
GPS2RX
0 Ohm
R13
MACRX
VDDIO 1SCK2
VSS_1 3
SDI4
SDO5
CSB 6
INT7
VSS_2 8VSS_3 9
VDD 10
U4
BMP388
GND
SDA
SCL
PRESSURE SENSOR
VCC4 SCL 1
SDA 3
WP5 GND 2
U7
AT24MAC402-STUM-T
SDA
SCL
+3.3V
GND
C59
0.1uF
C61
0.1uF
C880.1uF C900.1uF
C570.1uF
C250.1uF
C230.1uF C240.1uF
GND GND
+3.3V_CLEAN +3.3V_CLEAN
+3.3V
GND
EXT_EEPROM_WP
R37
10K
EEPROM
PIC2301 
PIC2302 
COC23 
PIC2401 
PIC2402 
COC24 
PIC2501 
PIC2502 
COC25 
PIC5601 
PIC5602 
COC56 
PIC5701 
PIC5702 
COC57 
PIC5801 
PIC5802 
COC58 
PIC5901 
PIC5902 
COC59 
PIC6001 
PIC6002 
COC60 
PIC6101 
PIC6102 
COC61 
PIC8501 
PIC8502 
COC85 
PIC8601 
PIC8602 
COC86 
PIC8701 
PIC8702 
COC87 
PIC8801 
PIC8802 COC88 PIC8901 
PIC8902 
COC89 
PIC9001 
PIC9002 COC90 
PIC9101 
PIC9102 
COC91 PIC9201 
PIC9202 
COC92 
PIJ401 
PIJ402 
PIJ403 
PIJ404 
PIJ405 
COJ4 
PIJP101 PIJP102 PIJP103 
COJP1 
PIJP201 PIJP202 PIJP203 
COJP2 
PIR1001 PIR1002 
COR10 
PIR1101 PIR1102 
COR11 
PIR1201 PIR1202 
COR12 
PIR1301 PIR1302 
COR13 
PIR3701 
PIR3702 
COR37 
PIR4301 PIR4302 
COR43 
PIU401 
PIU402 
PIU403 
PIU404 
PIU405 
PIU406 
PIU407 
PIU408 
PIU409 
PIU4010 
COU4 
PIU701 
PIU702 
PIU703 
PIU704 
PIU705 
COU7 
PIU801 
PIU802 
PIU803 
PIU804 
PIU805 
PIU806 
PIU807 
PIU808 
PIU809 
PIU8010 
PIU8011 
PIU8012 
PIU8013 
PIU8014 PIU8015 
PIU8016 
PIU8017 
PIU8018 
PIU8019 
PIU8020 
PIU8021 
PIU8022 
PIU8023 
PIU8024 
PIU8025 
PIU8026 
PIU8027 
PIU8028 
COU8 
PIU901 
PIU902 
PIU903 
PIU904 PIU905 
PIU906 
PIU907 
PIU908 
COU9 
PIU1401 
PIU1402 
PIU1403 
PIU1404 PIU1405 
PIU1406 
PIU1407 
PIU1408 
COU14 
PIU1601 
PIU1602 
PIU1603 
PIU1604 
PIU1605 
PIU1606 
PIU1607 
PIU1608 
PIU1609 
PIU16010 
PIU16011 
PIU16012 
PIU16013 
PIU16014 
PIU16015 
PIU16016 
COU16 
PIX101 
PIX102 PIX103 
PIX104 
COX1 



1
1
2
2
3
3
4
4
5
5
6
6
D D
C C
B B
A A
timingcard.com
6SHEET OF 7
MAC_TX
MAC_RX
MAC_BITEMAC_RF_OUT
MAC_FREQ_CTRL
MAC_PPS_IN1+
MAC_PPS_IN1-
MAC_PPS_IN0+
MAC_PPS_IN0-
MAC_USB+
MAC_USB-
MAC_USB_PWR
MAC_PPS_OUT+
MAC_PPS_OUT-
MAC_ALARM
GND
GND
+5.0V
GND
MAC
10uF
C62
FREQ CTRL INP1
GND (CASE)P2
RF OUTP3
GND (SUPPLY & SIGNAL)P4 VCC P5BITE P6RS-232 TX P7RS-232 RX P8
RV-3049-C3
U10A
RV-3049-C3
PPS-IN 1+1 USB DATA + 2
PPS-IN 1-3 USB DATA - 4
PPS-IN 0+5 USB POWER 6
PPS-IN 0-7
GND 8
GND 9
NC10
NC11
NC12
NC13
NC14
GND 15NC16
PPS-OUT + 17
NC18
PPS-OUT - 19
ALARM 20
U10B
DCXO2
DCXO1
1.0UF
C65
0.01uF
C67
220 OHM
445-1565-1-ND
FB3
220 OHM
445-1565-1-ND
FB2
+3.3V_CLEAN
GND
GND
SDA
SCL
OE_5356
SDA
SCL
10K
R42
+3.3V_CLEAN
GND
22uF
C72
22uF
C73
22uF
C74
22uF
C75
1.0UF
C84
0.01uF
C76
GND
+3.3V_CLEAN
+3.3V +3.3V_CLEAN
GND
SCL2
OE1
NC 3
GND4
10MHZ
A05
CLK 6
NC 7
NC 8
VDD 9
SDA10
U13
SCL3
NC 1
NC 3
GND5
10MHZ
STATUS 2
CLK 6
NC 7
NC 8
VDD10
SDA4
U11
5721_STATUS
RTC
GND
RTC_MFP
SDA
SCL
TUNE1
1 PPS OUT 10
10 MHZ OUT 12
BITE 4
TX5 RX6
VCC7 GND 8
1 PPS IN9
U10AL
SA.45s
GND
+3.3V_CLEAN
+3.3V_CLEAN
MAC_RX
MAC_TX
MAC_PPSin
MAC_BITE
MAC_PPSout
MAC_10Mout
GPS1_TP1
32kHz 1
VCC2
INT/SQW 3
RST 4
GND 13
VBAT14
SDA15 SCL16
U3A
DS3231SN
+3.3V_CLEAN
21 +
-
BT1
BU2032SM-BT-GTR
GND
0 Ohm
R17
MACPPS
C660.1uF
C770.1uF C780.1uF C790.1uF C800.1uF C810.1uF C820.1uF C830.1uF
C63
0.1uF
PIBT101 
PIBT102 COBT1 
PIC6201 
PIC6202 
COC62 
PIC6301 
PIC6302 COC63 
PIC6501 
PIC6502 
COC65 
PIC6601 
PIC6602 
COC66 
PIC6701 
PIC6702 
COC67 
PIC7201 
PIC7202 
COC72 PIC7301 
PIC7302 
COC73 PIC7401 
PIC7402 
COC74 PIC7501 
PIC7502 
COC75 
PIC7601 
PIC7602 
COC76 PIC7701 
PIC7702 
COC77 
PIC7801 
PIC7802 
COC78 
PIC7901 
PIC7902 
COC79 
PIC8001 
PIC8002 
COC80 
PIC8101 
PIC8102 
COC81 
PIC8201 
PIC8202 
COC82 
PIC8301 
PIC8302 
COC83 
PIC8401 
PIC8402 
COC84 
PIFB201 PIFB202 
COFB2 
PIFB301 PIFB302 
COFB3 
PIR1701 
PIR1702 
COR17 
PIR4201 PIR4202 
COR42 
PIU301 
PIU302 
PIU303 
PIU304 
PIU3013 
PIU3014 
PIU3015 
PIU3016 
COU3A 
PIU100P1 
PIU100P2 
PIU100P3 
PIU100P4 PIU100P5 
PIU100P6 
PIU100P7 
PIU100P8 
COU10A 
PIU1001 PIU1002 
PIU1003 PIU1004 
PIU1005 PIU1006 
PIU1007 
PIU1008 
PIU1009 
PIU10010 
PIU10011 
PIU10012 
PIU10013 
PIU10014 
PIU10015 
PIU10016 
PIU10017 
PIU10018 
PIU10019 
PIU10020 
COU10B 
PIU10AL01 
PIU10AL04 
PIU10AL05 
PIU10AL06 
PIU10AL07 PIU10AL08 
PIU10AL09 PIU10AL010 
PIU10AL012 
COU10AL 
PIU1101 
PIU1102 
PIU1103 
PIU1104 
PIU1105 
PIU1106 
PIU1107 
PIU1108 
PIU11010 
COU11 
PIU1301 
PIU1302 
PIU1303 
PIU1304 
PIU1305 
PIU1306 
PIU1307 
PIU1308 
PIU1309 
PIU13010 
COU13 



1
1
2
2
3
3
4
4
5
5
6
6
D D
C C
B B
A A
timingcard.com
7SHEET OF 7
+5.0V
GND
KEY2
LED4
LED3
LED2
LED1
CSN
MISO
MOSI
SCK
GPS2_RST
GPS2_TP2
GPS2_TP1
+5.0V
GND
GPS1_RST
GPS1_TP1
GPS1_TP2
IMU_BOOT
IMU_CLKSEL0
IMU_INT
IMU_NRST
IMU_PS0
IMU_PS1
GND
UART1_RXD
UART1_TXD
GPS1_RX
MAC_ALARM
MAC_BITE
MAC_FREQ_CTRL
MAC_PPS_IN0+
MAC_PPS_IN0-
MAC_PPS_IN1+
MAC_PPS_IN1-
MAC_PPS_OUT+
MAC_PPS_OUT-
MAC_RF_OUT
ANT1
ANT2
ANT3
ANT4
SDA
SCL
GND
DCXO2
GPS1_TX
MAC_RX
MAC_TX
MAC_USB+
MAC_USB-
MAC_USB_PWR
OE_5356
DCXO1
5721_STATUS
GND
PCIE_PERST
KEY1
FPGA_TCK
FPGA_TDO
IMU_ENV_SCL
IMU_ENV_SDA
RTC_MFP
GPS2_RX
GND
FPGA_TDI
FPGA_TMS
GPS2_TX
GND
PCIE_TX3_P
PCIE_TX3_N
PCIE_RX3_P
PCIE_RX3_N
PCIE_TX0_P
PCIE_TX0_N
PCIE_RX0_P
PCIE_RX0_N
GND
PCIE_TX2_P
PCIE_TX2_N
PCIE_RX2_P
PCIE_RX2_N
PCIE_TX1_P
PCIE_TX1_N
PCIE_RX1_P
PCIE_RX1_N
PCIE_CLK_P
PCIE_CLK_N
MAC_PPSin
MAC_PPSout
MAC_10Mout
1A-1 2 A-2
3A-3 4 A-4
5A-5 6 A-6
7A-7 8 A-8
9A-9 10 A-10
11A-11 12 A-12
13A-13 14 A-14
15A-15 16 A-16
17A-17 18 A-18
19A-19 20 A-20
21A-21 22 A-22
23A-23 24 A-24
25A-25 26 A-26
27A-27 28 A-28
29A-29 30 A-30
31A-31 32 A-32
33A-33 34 A-34
35A-35 36 A-36
37A-37 38 A-38
39A-39 40 A-40
41A-41 42 A-42
43A-43 44 A-44
45A-45 46 A-46
47A-47 48 A-48
49A-49 50 A-50
51A-51 52 A-52
53A-53 54 A-54
55A-55 56 A-56
57A-57 58 A-58
59A-59 60 A-60
61A-61 62 A-62
63A-63 64 A-64
65A-65 66 A-66
67A-67 68 A-68
69A-69 70 A-70
71A-71 72 A-72
73A-73 74 A-74
75A-75 76 A-76
77A-77 78 A-78
79A-79 80 A-80
81A-81 82 A-82
83A-83 84 A-84
P1A
FPGA_CONN
1B-1 2 B-2
3B-3 4 B-4
5B-5 6 B-6
7B-7 8 B-8
9B-9 10 B-10
11B-11 12 B-12
13B-13 14 B-14
15B-15 16 B-16
17B-17 18 B-18
19B-19 20 B-20
21B-21 22 B-22
23B-23 24 B-24
25B-25 26 B-26
27B-27 28 B-28
29B-29 30 B-30
31B-31 32 B-32
33B-33 34 B-34
35B-35 36 B-36
37B-37 38 B-38
39B-39 40 B-40
41B-41 42 B-42
43B-43 44 B-44
45B-45 46 B-46
47B-47 48 B-48
49B-49 50 B-50
51B-51 52 B-52
53B-53 54 B-54
55B-55 56 B-56
57B-57 58 B-58
59B-59 60 B-60
61B-61 62 B-62
63B-63 64 B-64
65B-65 66 B-66
67B-67 68 B-68
69B-69 70 B-70
71B-71 72 B-72
73B-73 74 B-74
75B-75 76 B-76
77B-77 78 B-78
79B-79 80 B-80
81B-81 82 B-82
83B-83 84 B-84
P1B
FPGA_CONN
1C-1 2 C-2
3C-3 4 C-4
5C-5 6 C-6
7C-7 8 C-8
9C-9 10 C-10
11C-11 12 C-12
13C-13 14 C-14
15C-15 16 C-16
17C-17 18 C-18
19C-19 20 C-20
21C-21 22 C-22
23C-23 24 C-24
25C-25 26 C-26
27C-27 28 C-28
29C-29 30 C-30
31C-31 32 C-32
33C-33 34 C-34
35C-35 36 C-36
37C-37 38 C-38
39C-39 40 C-40
41C-41 42 C-42
43C-43 44 C-44
45C-45 46 C-46
47C-47 48 C-48
49C-49 50 C-50
51C-51 52 C-52
53C-53 54 C-54
55C-55 56 C-56
57C-57 58 C-58
59C-59 60 C-60
61C-61 62 C-62
63C-63 64 C-64
65C-65 66 C-66
67C-67 68 C-68
69C-69 70 C-70
71C-71 72 C-72
73C-73 74 C-74
75C-75 76 C-76
77C-77 78 C-78
79C-79 80 C-80
81C-81 82 C-82
83C-83 84 C-84
P1C
FPGA_CONN
1D-1 2 D-2
3D-3 4 D-4
5D-5 6 D-6
7D-7 8 D-8
9D-9 10 D-10
11D-11 12 D-12
13D-13 14 D-14
15D-15 16 D-16
17D-17 18 D-18
19D-19 20 D-20
21D-21 22 D-22
23D-23 24 D-24
25D-25 26 D-26
27D-27 28 D-28
29D-29 30 D-30
31D-31 32 D-32
33D-33 34 D-34
35D-35 36 D-36
37D-37 38 D-38
39D-39 40 D-40
41D-41 42 D-42
43D-43 44 D-44
45D-45 46 D-46
47D-47 48 D-48
49D-49 50 D-50
51D-51 52 D-52
53D-53 54 D-54
55D-55 56 D-56
57D-57 58 D-58
59D-59 60 D-60
61D-61 62 D-62
63D-63 64 D-64
65D-65 66 D-66
67D-67 68 D-68
69D-69 70 D-70
71D-71 72 D-72
73D-73 74 D-74
75D-75 76 D-76
77D-77 78 D-78
79D-79 80 D-80
81D-81 82 D-82
83D-83 84 D-84
P1D
FPGA_CONN
EXT_EEPROM_WP
PIP10A01 PIP10A02 
PIP10A03 PIP10A04 
PIP10A05 PIP10A06 
PIP10A07 PIP10A08 
PIP10A09 PIP10A010 
PIP10A011 PIP10A012 
PIP10A013 PIP10A014 
PIP10A015 PIP10A016 
PIP10A017 PIP10A018 
PIP10A019 PIP10A020 
PIP10A021 PIP10A022 
PIP10A023 PIP10A024 
PIP10A025 PIP10A026 
PIP10A027 PIP10A028 
PIP10A029 PIP10A030 
PIP10A031 PIP10A032 
PIP10A033 PIP10A034 
PIP10A035 PIP10A036 
PIP10A037 PIP10A038 
PIP10A039 PIP10A040 
PIP10A041 PIP10A042 
PIP10A043 PIP10A044 
PIP10A045 PIP10A046 
PIP10A047 PIP10A048 
PIP10A049 PIP10A050 
PIP10A051 PIP10A052 
PIP10A053 PIP10A054 
PIP10A055 PIP10A056 
PIP10A057 PIP10A058 
PIP10A059 PIP10A060 
PIP10A061 PIP10A062 
PIP10A063 PIP10A064 
PIP10A065 PIP10A066 
PIP10A067 PIP10A068 
PIP10A069 PIP10A070 
PIP10A071 PIP10A072 
PIP10A073 PIP10A074 
PIP10A075 PIP10A076 
PIP10A077 PIP10A078 
PIP10A079 PIP10A080 
PIP10A081 PIP10A082 
PIP10A083 PIP10A084 
COP1A 
PIP10B01 PIP10B02 
PIP10B03 PIP10B04 
PIP10B05 PIP10B06 
PIP10B07 PIP10B08 
PIP10B09 PIP10B010 
PIP10B011 PIP10B012 
PIP10B013 PIP10B014 
PIP10B015 PIP10B016 
PIP10B017 PIP10B018 
PIP10B019 PIP10B020 
PIP10B021 PIP10B022 
PIP10B023 PIP10B024 
PIP10B025 PIP10B026 
PIP10B027 PIP10B028 
PIP10B029 PIP10B030 
PIP10B031 PIP10B032 
PIP10B033 PIP10B034 
PIP10B035 PIP10B036 
PIP10B037 PIP10B038 
PIP10B039 PIP10B040 
PIP10B041 PIP10B042 
PIP10B043 PIP10B044 
PIP10B045 PIP10B046 
PIP10B047 PIP10B048 
PIP10B049 PIP10B050 
PIP10B051 PIP10B052 
PIP10B053 PIP10B054 
PIP10B055 PIP10B056 
PIP10B057 PIP10B058 
PIP10B059 PIP10B060 
PIP10B061 PIP10B062 
PIP10B063 PIP10B064 
PIP10B065 PIP10B066 
PIP10B067 PIP10B068 
PIP10B069 PIP10B070 
PIP10B071 PIP10B072 
PIP10B073 PIP10B074 
PIP10B075 PIP10B076 
PIP10B077 PIP10B078 
PIP10B079 PIP10B080 
PIP10B081 PIP10B082 
PIP10B083 PIP10B084 
COP1B 
PIP10C01 PIP10C02 
PIP10C03 PIP10C04 
PIP10C05 PIP10C06 
PIP10C07 PIP10C08 
PIP10C09 PIP10C010 
PIP10C011 PIP10C012 
PIP10C013 PIP10C014 
PIP10C015 PIP10C016 
PIP10C017 PIP10C018 
PIP10C019 PIP10C020 
PIP10C021 PIP10C022 
PIP10C023 PIP10C024 
PIP10C025 PIP10C026 
PIP10C027 PIP10C028 
PIP10C029 PIP10C030 
PIP10C031 PIP10C032 
PIP10C033 PIP10C034 
PIP10C035 PIP10C036 
PIP10C037 PIP10C038 
PIP10C039 PIP10C040 
PIP10C041 PIP10C042 
PIP10C043 PIP10C044 
PIP10C045 PIP10C046 
PIP10C047 PIP10C048 
PIP10C049 PIP10C050 
PIP10C051 PIP10C052 
PIP10C053 PIP10C054 
PIP10C055 PIP10C056 
PIP10C057 PIP10C058 
PIP10C059 PIP10C060 
PIP10C061 PIP10C062 
PIP10C063 PIP10C064 
PIP10C065 PIP10C066 
PIP10C067 PIP10C068 
PIP10C069 PIP10C070 
PIP10C071 PIP10C072 
PIP10C073 PIP10C074 
PIP10C075 PIP10C076 
PIP10C077 PIP10C078 
PIP10C079 PIP10C080 
PIP10C081 PIP10C082 
PIP10C083 PIP10C084 
COP1C 
PIP10D01 PIP10D02 
PIP10D03 PIP10D04 
PIP10D05 PIP10D06 
PIP10D07 PIP10D08 
PIP10D09 PIP10D010 
PIP10D011 PIP10D012 
PIP10D013 PIP10D014 
PIP10D015 PIP10D016 
PIP10D017 PIP10D018 
PIP10D019 PIP10D020 
PIP10D021 PIP10D022 
PIP10D023 PIP10D024 
PIP10D025 PIP10D026 
PIP10D027 PIP10D028 
PIP10D029 PIP10D030 
PIP10D031 PIP10D032 
PIP10D033 PIP10D034 
PIP10D035 PIP10D036 
PIP10D037 PIP10D038 
PIP10D039 PIP10D040 
PIP10D041 PIP10D042 
PIP10D043 PIP10D044 
PIP10D045 PIP10D046 
PIP10D047 PIP10D048 
PIP10D049 PIP10D050 
PIP10D051 PIP10D052 
PIP10D053 PIP10D054 
PIP10D055 PIP10D056 
PIP10D057 PIP10D058 
PIP10D059 PIP10D060 
PIP10D061 PIP10D062 
PIP10D063 PIP10D064 
PIP10D065 PIP10D066 
PIP10D067 PIP10D068 
PIP10D069 PIP10D070 
PIP10D071 PIP10D072 
PIP10D073 PIP10D074 
PIP10D075 PIP10D076 
PIP10D077 PIP10D078 
PIP10D079 PIP10D080 
PIP10D081 PIP10D082 
PIP10D083 PIP10D084 
COP1D 